# T6G (Grand Teton) — schematic netlist excerpt (pin names and nets, part order shuffled) for the footprints in the layout excerpt that follows; sources: Cadence DE-HDL packaged netlist, KiCad conversion of 04192023_DAF0TMB3IC0_F0TG_MB_C_brd_V02_OCP.brd

PR384  Q_RES  0 5% CHIP  pkg 0402LF  page 224 : A = VSENSE_PVDD11_S3_P1_DP ; B = VSENSE_PVDD11_S3_P1_R
C6023  Q_CAP  0.1UF 25V 10% X7R  pkg 0402  page 180 : A = USB3_CPU0_BMC_HUB1_TX_DP ; B = USB3_CPU0_BMC_TX_BUF_C_DP

(kicad_pcb
	(version 20260206)
	(generator "pcbnew")
	(generator_version "10.0")
	(general
		(thickness 1.6)
		(legacy_teardrops no)
	)
	(paper "A4")
	(title_block
		(title "04192023_DAF0TMB3IC0_F0TG_MB_C_brd_V02_OCP.brd")
		(comment 1 "Grand Teton / footprints 4124-4125 of 8354")
	)
	(layers
		(0 "F.Cu" signal "TOP")
		(4 "In1.Cu" signal "GND")
		(6 "In2.Cu" signal "IN1")
		(8 "In3.Cu" signal "GND1")
		(10 "In4.Cu" signal "IN2")
		(12 "In5.Cu" signal "GND2")
		(14 "In6.Cu" signal "IN3")
		(16 "In7.Cu" signal "GND3")
		(18 "In8.Cu" signal "VCC")
		(20 "In9.Cu" signal "VCC1")
		(22 "In10.Cu" signal "GND4")
		(24 "In11.Cu" signal "IN4")
		(26 "In12.Cu" signal "GND5")
		(28 "In13.Cu" signal "IN5")
		(30 "In14.Cu" signal "GND6")
		(32 "In15.Cu" signal "IN6")
		(34 "In16.Cu" signal "GND7")
		(2 "B.Cu" signal "BOTTOM")
		(9 "F.Adhes" user "F.Adhesive")
		(11 "B.Adhes" user "B.Adhesive")
		(13 "F.Paste" user "Package Geometry/Pastemask Top")
		(15 "B.Paste" user "Package Geometry/Pastemask Bottom")
		(5 "F.SilkS" user "Ref Des/Silkscreen Top")
		(7 "B.SilkS" user "Ref Des/Silkscreen Bottom")
		(1 "F.Mask" user "Board Geometry/Soldermask Top")
		(3 "B.Mask" user "Board Geometry/Soldermask Bottom")
		(17 "Dwgs.User" user "User.Drawings")
		(19 "Cmts.User" user "User.Comments")
		(21 "Eco1.User" user "User.Eco1")
		(23 "Eco2.User" user "User.Eco2")
		(25 "Edge.Cuts" user "Board Geometry/Outline")
		(27 "Margin" user)
		(31 "F.CrtYd" user "Package Geometry/Place Bound Top")
		(29 "B.CrtYd" user "Package Geometry/Place Bound Bottom")
		(35 "F.Fab" user "Ref Des/Assembly Top")
		(33 "B.Fab" user "Ref Des/Assembly Bottom")
	)
	(footprint ""
		(layer "F.Cu")
		(at 123.35637 -36.675568 180)
		(property "Reference" "C6023"
			(at 0 0 180)
			(layer "F.SilkS")
			(hide yes)
			(effects
				(font
					(size 1.27 1.27)
				)
			)
		)
		(property "Value" ""
			(at 0 0 180)
			(layer "F.Fab")
			(effects
				(font
					(size 1.27 1.27)
				)
			)
		)
		(duplicate_pad_numbers_are_jumpers no)
		(fp_line
			(start 0.7874 0.4064)
			(end -0.7874 0.4064)
			(stroke
				(width 0.1524)
				(type default)
			)
			(layer "F.SilkS")
		)
		(fp_line
			(start 0.7874 -0.4064)
			(end 0.7874 0.4064)
			(stroke
				(width 0.1524)
				(type default)
			)
			(layer "F.SilkS")
		)
		(fp_line
			(start -0.7874 0.4064)
			(end -0.7874 -0.4064)
			(stroke
				(width 0.1524)
				(type default)
			)
			(layer "F.SilkS")
		)
		(fp_line
			(start -0.7874 -0.4064)
			(end 0.7874 -0.4064)
			(stroke
				(width 0.1524)
				(type default)
			)
			(layer "F.SilkS")
		)
		(fp_line
			(start 0.6858 0.3048)
			(end 0.1016 0.3048)
			(stroke
				(width 0.1)
				(type default)
			)
			(layer "F.Fab")
		)
		(fp_line
			(start 0.6858 -0.3048)
			(end 0.6858 0.3048)
			(stroke
				(width 0.1)
				(type default)
			)
			(layer "F.Fab")
		)
		(fp_line
			(start 0.1016 0.3048)
			(end 0.1016 0.2794)
			(stroke
				(width 0.1)
				(type default)
			)
			(layer "F.Fab")
		)
		(fp_line
			(start 0.1016 0.2794)
			(end -0.1016 0.2794)
			(stroke
				(width 0.1)
				(type default)
			)
			(layer "F.Fab")
		)
		(fp_line
			(start 0.1016 -0.2794)
			(end 0.1016 -0.3048)
			(stroke
				(width 0.1)
				(type default)
			)
			(layer "F.Fab")
		)
		(fp_line
			(start 0.1016 -0.3048)
			(end 0.6858 -0.3048)
			(stroke
				(width 0.1)
				(type default)
			)
			(layer "F.Fab")
		)
		(fp_line
			(start -0.1016 0.3048)
			(end -0.6858 0.3048)
			(stroke
				(width 0.1)
				(type default)
			)
			(layer "F.Fab")
		)
		(fp_line
			(start -0.1016 0.2794)
			(end -0.1016 0.3048)
			(stroke
				(width 0.1)
				(type default)
			)
			(layer "F.Fab")
		)
		(fp_line
			(start -0.1016 -0.2794)
			(end 0.1016 -0.2794)
			(stroke
				(width 0.1)
				(type default)
			)
			(layer "F.Fab")
		)
		(fp_line
			(start -0.1016 -0.3048)
			(end -0.1016 -0.2794)
			(stroke
				(width 0.1)
				(type default)
			)
			(layer "F.Fab")
		)
		(fp_line
			(start -0.6858 0.3048)
			(end -0.6858 -0.3048)
			(stroke
				(width 0.1)
				(type default)
			)
			(layer "F.Fab")
		)
		(fp_line
			(start -0.6858 -0.3048)
			(end -0.1016 -0.3048)
			(stroke
				(width 0.1)
				(type default)
			)
			(layer "F.Fab")
		)
		(pad "1" smd rect
			(at -0.40005 0)
			(size 0.4572 0.508)
			(layers "F.Cu" "F.Mask" "F.Paste")
			(net "USB3_CPU0_BMC_HUB1_TX_DP")
		)
		(pad "2" smd rect
			(at 0.40005 0)
			(size 0.4572 0.508)
			(layers "F.Cu" "F.Mask" "F.Paste")
			(net "USB3_CPU0_BMC_TX_BUF_C_DP")
		)
	)
	(footprint ""
		(layer "F.Cu")
		(at 159.182562 -343.327736 90)
		(property "Reference" "PR384"
			(at 0 0 90)
			(layer "F.SilkS")
			(hide yes)
			(effects
				(font
					(size 1.27 1.27)
				)
			)
		)
		(property "Value" ""
			(at 0 0 90)
			(layer "F.Fab")
			(effects
				(font
					(size 1.27 1.27)
				)
			)
		)
		(duplicate_pad_numbers_are_jumpers no)
		(fp_line
			(start 0.7874 -0.4064)
			(end 0.7874 0.4064)
			(stroke
				(width 0.1524)
				(type default)
			)
			(layer "F.SilkS")
		)
		(fp_line
			(start -0.7874 -0.4064)
			(end 0.7874 -0.4064)
			(stroke
				(width 0.1524)
				(type default)
			)
			(layer "F.SilkS")
		)
		(fp_line
			(start 0.7874 0.4064)
			(end -0.7874 0.4064)
			(stroke
				(width 0.1524)
				(type default)
			)
			(layer "F.SilkS")
		)
		(fp_line
			(start -0.7874 0.4064)
			(end -0.7874 -0.4064)
			(stroke
				(width 0.1524)
				(type default)
			)
			(layer "F.SilkS")
		)
		(fp_line
			(start -0.12065 -0.305054)
			(end -0.12065 -0.2794)
			(stroke
				(width 0.1)
				(type default)
			)
			(layer "F.Fab")
		)
		(fp_line
			(start -0.67945 -0.305054)
			(end -0.12065 -0.305054)
			(stroke
				(width 0.1)
				(type default)
			)
			(layer "F.Fab")
		)
		(fp_line
			(start 0.67945 -0.3048)
			(end 0.67945 0.3048)
			(stroke
				(width 0.1)
				(type default)
			)
			(layer "F.Fab")
		)
		(fp_line
			(start 0.12065 -0.3048)
			(end 0.67945 -0.3048)
			(stroke
				(width 0.1)
				(type default)
			)
			(layer "F.Fab")
		)
		(fp_line
			(start 0.12065 -0.2794)
			(end 0.12065 -0.3048)
			(stroke
				(width 0.1)
				(type default)
			)
			(layer "F.Fab")
		)
		(fp_line
			(start -0.12065 -0.2794)
			(end 0.12065 -0.2794)
			(stroke
				(width 0.1)
				(type default)
			)
			(layer "F.Fab")
		)
		(fp_line
			(start 0.120396 0.2794)
			(end -0.12065 0.2794)
			(stroke
				(width 0.1)
				(type default)
			)
			(layer "F.Fab")
		)
		(fp_line
			(start -0.12065 0.2794)
			(end -0.12065 0.3048)
			(stroke
				(width 0.1)
				(type default)
			)
			(layer "F.Fab")
		)
		(fp_line
			(start 0.67945 0.3048)
			(end 0.120396 0.3048)
			(stroke
				(width 0.1)
				(type default)
			)
			(layer "F.Fab")
		)
		(fp_line
			(start 0.120396 0.3048)
			(end 0.120396 0.2794)
			(stroke
				(width 0.1)
				(type default)
			)
			(layer "F.Fab")
		)
		(fp_line
			(start -0.12065 0.3048)
			(end -0.67945 0.3048)
			(stroke
				(width 0.1)
				(type default)
			)
			(layer "F.Fab")
		)
		(fp_line
			(start -0.67945 0.3048)
			(end -0.67945 -0.305054)
			(stroke
				(width 0.1)
				(type default)
			)
			(layer "F.Fab")
		)
		(pad "1" smd circle
			(at -0.40005 0 90)
			(size 0 0)
			(layers "F.Cu" "F.Mask" "F.Paste")
			(net "VSENSE_PVDD11_S3_P1_DP")
		)
		(pad "2" smd circle
			(at 0.40005 0 90)
			(size 0 0)
			(layers "F.Cu" "F.Mask" "F.Paste")
			(net "VSENSE_PVDD11_S3_P1_R")
		)
	)
)
